# T6G (Grand Teton) — schematic netlist excerpt (pin names and nets, part order shuffled) for the footprints in the layout excerpt that follows; sources: Cadence DE-HDL packaged netlist, KiCad conversion of 04192023_DAF0TMB3IC0_F0TG_MB_C_brd_V02_OCP.brd

C1059  Q_CAP  0.1UF 25V 10% X7R  pkg 0402  page 136 : A = P3V3_AUX ; B = GND
C1833  Q_CAP  0.1UF 25V 10% X7R  pkg 0402  page 137 : A = P12V_OCP_V3_2_R ; B = GND

(kicad_pcb
	(version 20260206)
	(generator "pcbnew")
	(generator_version "10.0")
	(general
		(thickness 1.6)
		(legacy_teardrops no)
	)
	(paper "A4")
	(title_block
		(title "04192023_DAF0TMB3IC0_F0TG_MB_C_brd_V02_OCP.brd")
		(comment 1 "Grand Teton / footprints 1610-1611 of 8354")
	)
	(layers
		(0 "F.Cu" signal "TOP")
		(4 "In1.Cu" signal "GND")
		(6 "In2.Cu" signal "IN1")
		(8 "In3.Cu" signal "GND1")
		(10 "In4.Cu" signal "IN2")
		(12 "In5.Cu" signal "GND2")
		(14 "In6.Cu" signal "IN3")
		(16 "In7.Cu" signal "GND3")
		(18 "In8.Cu" signal "VCC")
		(20 "In9.Cu" signal "VCC1")
		(22 "In10.Cu" signal "GND4")
		(24 "In11.Cu" signal "IN4")
		(26 "In12.Cu" signal "GND5")
		(28 "In13.Cu" signal "IN5")
		(30 "In14.Cu" signal "GND6")
		(32 "In15.Cu" signal "IN6")
		(34 "In16.Cu" signal "GND7")
		(2 "B.Cu" signal "BOTTOM")
		(9 "F.Adhes" user "F.Adhesive")
		(11 "B.Adhes" user "B.Adhesive")
		(13 "F.Paste" user "Package Geometry/Pastemask Top")
		(15 "B.Paste" user "Package Geometry/Pastemask Bottom")
		(5 "F.SilkS" user "Ref Des/Silkscreen Top")
		(7 "B.SilkS" user "Ref Des/Silkscreen Bottom")
		(1 "F.Mask" user "Board Geometry/Soldermask Top")
		(3 "B.Mask" user "Board Geometry/Soldermask Bottom")
		(17 "Dwgs.User" user "User.Drawings")
		(19 "Cmts.User" user "User.Comments")
		(21 "Eco1.User" user "User.Eco1")
		(23 "Eco2.User" user "User.Eco2")
		(25 "Edge.Cuts" user "Board Geometry/Outline")
		(27 "Margin" user)
		(31 "F.CrtYd" user "Package Geometry/Place Bound Top")
		(29 "B.CrtYd" user "Package Geometry/Place Bound Bottom")
		(35 "F.Fab" user "Ref Des/Assembly Top")
		(33 "B.Fab" user "Ref Des/Assembly Bottom")
	)
	(footprint ""
		(layer "F.Cu")
		(at 65.3796 -14.8336 180)
		(property "Reference" "C1833"
			(at 0 0 180)
			(layer "F.SilkS")
			(hide yes)
			(effects
				(font
					(size 1.27 1.27)
				)
			)
		)
		(property "Value" ""
			(at 0 0 180)
			(layer "F.Fab")
			(effects
				(font
					(size 1.27 1.27)
				)
			)
		)
		(duplicate_pad_numbers_are_jumpers no)
		(fp_line
			(start 0.7874 0.4064)
			(end -0.7874 0.4064)
			(stroke
				(width 0.1524)
				(type default)
			)
			(layer "F.SilkS")
		)
		(fp_line
			(start 0.7874 -0.4064)
			(end 0.7874 0.4064)
			(stroke
				(width 0.1524)
				(type default)
			)
			(layer "F.SilkS")
		)
		(fp_line
			(start -0.7874 0.4064)
			(end -0.7874 -0.4064)
			(stroke
				(width 0.1524)
				(type default)
			)
			(layer "F.SilkS")
		)
		(fp_line
			(start -0.7874 -0.4064)
			(end 0.7874 -0.4064)
			(stroke
				(width 0.1524)
				(type default)
			)
			(layer "F.SilkS")
		)
		(fp_line
			(start 0.67945 0.3048)
			(end 0.120396 0.3048)
			(stroke
				(width 0.1)
				(type default)
			)
			(layer "F.Fab")
		)
		(fp_line
			(start 0.67945 -0.3048)
			(end 0.67945 0.3048)
			(stroke
				(width 0.1)
				(type default)
			)
			(layer "F.Fab")
		)
		(fp_line
			(start 0.12065 -0.2794)
			(end 0.12065 -0.3048)
			(stroke
				(width 0.1)
				(type default)
			)
			(layer "F.Fab")
		)
		(fp_line
			(start 0.12065 -0.3048)
			(end 0.67945 -0.3048)
			(stroke
				(width 0.1)
				(type default)
			)
			(layer "F.Fab")
		)
		(fp_line
			(start 0.120396 0.3048)
			(end 0.120396 0.2794)
			(stroke
				(width 0.1)
				(type default)
			)
			(layer "F.Fab")
		)
		(fp_line
			(start 0.120396 0.2794)
			(end -0.12065 0.2794)
			(stroke
				(width 0.1)
				(type default)
			)
			(layer "F.Fab")
		)
		(fp_line
			(start -0.12065 0.3048)
			(end -0.67945 0.3048)
			(stroke
				(width 0.1)
				(type default)
			)
			(layer "F.Fab")
		)
		(fp_line
			(start -0.12065 0.2794)
			(end -0.12065 0.3048)
			(stroke
				(width 0.1)
				(type default)
			)
			(layer "F.Fab")
		)
		(fp_line
			(start -0.12065 -0.2794)
			(end 0.12065 -0.2794)
			(stroke
				(width 0.1)
				(type default)
			)
			(layer "F.Fab")
		)
		(fp_line
			(start -0.12065 -0.305054)
			(end -0.12065 -0.2794)
			(stroke
				(width 0.1)
				(type default)
			)
			(layer "F.Fab")
		)
		(fp_line
			(start -0.67945 0.3048)
			(end -0.67945 -0.305054)
			(stroke
				(width 0.1)
				(type default)
			)
			(layer "F.Fab")
		)
		(fp_line
			(start -0.67945 -0.305054)
			(end -0.12065 -0.305054)
			(stroke
				(width 0.1)
				(type default)
			)
			(layer "F.Fab")
		)
		(pad "1" smd circle
			(at -0.40005 0 180)
			(size 0 0)
			(layers "F.Cu" "F.Mask" "F.Paste")
			(net "P12V_OCP_V3_2_R")
		)
		(pad "2" smd circle
			(at 0.40005 0 180)
			(size 0 0)
			(layers "F.Cu" "F.Mask" "F.Paste")
			(net "GND")
		)
	)
	(footprint ""
		(layer "F.Cu")
		(at 204.992986 -98.244914)
		(property "Reference" "C1059"
			(at 0 0 0)
			(layer "F.SilkS")
			(hide yes)
			(effects
				(font
					(size 1.27 1.27)
				)
			)
		)
		(property "Value" ""
			(at 0 0 0)
			(layer "F.Fab")
			(effects
				(font
					(size 1.27 1.27)
				)
			)
		)
		(duplicate_pad_numbers_are_jumpers no)
		(fp_line
			(start -0.7874 -0.4064)
			(end 0.7874 -0.4064)
			(stroke
				(width 0.1524)
				(type default)
			)
			(layer "F.SilkS")
		)
		(fp_line
			(start -0.7874 0.4064)
			(end -0.7874 -0.4064)
			(stroke
				(width 0.1524)
				(type default)
			)
			(layer "F.SilkS")
		)
		(fp_line
			(start 0.7874 -0.4064)
			(end 0.7874 0.4064)
			(stroke
				(width 0.1524)
				(type default)
			)
			(layer "F.SilkS")
		)
		(fp_line
			(start 0.7874 0.4064)
			(end -0.7874 0.4064)
			(stroke
				(width 0.1524)
				(type default)
			)
			(layer "F.SilkS")
		)
		(fp_line
			(start -0.67945 -0.305054)
			(end -0.12065 -0.305054)
			(stroke
				(width 0.1)
				(type default)
			)
			(layer "F.Fab")
		)
		(fp_line
			(start -0.67945 0.3048)
			(end -0.67945 -0.305054)
			(stroke
				(width 0.1)
				(type default)
			)
			(layer "F.Fab")
		)
		(fp_line
			(start -0.12065 -0.305054)
			(end -0.12065 -0.2794)
			(stroke
				(width 0.1)
				(type default)
			)
			(layer "F.Fab")
		)
		(fp_line
			(start -0.12065 -0.2794)
			(end 0.12065 -0.2794)
			(stroke
				(width 0.1)
				(type default)
			)
			(layer "F.Fab")
		)
		(fp_line
			(start -0.12065 0.2794)
			(end -0.12065 0.3048)
			(stroke
				(width 0.1)
				(type default)
			)
			(layer "F.Fab")
		)
		(fp_line
			(start -0.12065 0.3048)
			(end -0.67945 0.3048)
			(stroke
				(width 0.1)
				(type default)
			)
			(layer "F.Fab")
		)
		(fp_line
			(start 0.120396 0.2794)
			(end -0.12065 0.2794)
			(stroke
				(width 0.1)
				(type default)
			)
			(layer "F.Fab")
		)
		(fp_line
			(start 0.120396 0.3048)
			(end 0.120396 0.2794)
			(stroke
				(width 0.1)
				(type default)
			)
			(layer "F.Fab")
		)
		(fp_line
			(start 0.12065 -0.3048)
			(end 0.67945 -0.3048)
			(stroke
				(width 0.1)
				(type default)
			)
			(layer "F.Fab")
		)
		(fp_line
			(start 0.12065 -0.2794)
			(end 0.12065 -0.3048)
			(stroke
				(width 0.1)
				(type default)
			)
			(layer "F.Fab")
		)
		(fp_line
			(start 0.67945 -0.3048)
			(end 0.67945 0.3048)
			(stroke
				(width 0.1)
				(type default)
			)
			(layer "F.Fab")
		)
		(fp_line
			(start 0.67945 0.3048)
			(end 0.120396 0.3048)
			(stroke
				(width 0.1)
				(type default)
			)
			(layer "F.Fab")
		)
		(pad "1" smd circle
			(at -0.40005 0)
			(size 0 0)
			(layers "F.Cu" "F.Mask" "F.Paste")
			(net "P3V3_AUX")
		)
		(pad "2" smd circle
			(at 0.40005 0)
			(size 0 0)
			(layers "F.Cu" "F.Mask" "F.Paste")
			(net "GND")
		)
	)
)
